(kicad_pcb
	(version 20260206)
	(generator "pcbnew")
	(generator_version "10.0")
	(general
		(thickness 1.6)
		(legacy_teardrops no)
	)
	(paper "A4")
	(title_block
		(title "04192023_DAF0TMB3IC0_F0TG_MB_C_brd_V02_OCP.brd")
		(comment 1 "Grand Teton / footprints 1505-1510 of 8354")
	)
	(layers
		(0 "F.Cu" signal "TOP")
		(4 "In1.Cu" signal "GND")
		(6 "In2.Cu" signal "IN1")
		(8 "In3.Cu" signal "GND1")
		(10 "In4.Cu" signal "IN2")
		(12 "In5.Cu" signal "GND2")
		(14 "In6.Cu" signal "IN3")
		(16 "In7.Cu" signal "GND3")
		(18 "In8.Cu" signal "VCC")
		(20 "In9.Cu" signal "VCC1")
		(22 "In10.Cu" signal "GND4")
		(24 "In11.Cu" signal "IN4")
		(26 "In12.Cu" signal "GND5")
		(28 "In13.Cu" signal "IN5")
		(30 "In14.Cu" signal "GND6")
		(32 "In15.Cu" signal "IN6")
		(34 "In16.Cu" signal "GND7")
		(2 "B.Cu" signal "BOTTOM")
		(9 "F.Adhes" user "F.Adhesive")
		(11 "B.Adhes" user "B.Adhesive")
		(13 "F.Paste" user "Package Geometry/Pastemask Top")
		(15 "B.Paste" user "Package Geometry/Pastemask Bottom")
		(5 "F.SilkS" user "Ref Des/Silkscreen Top")
		(7 "B.SilkS" user "Ref Des/Silkscreen Bottom")
		(1 "F.Mask" user "Board Geometry/Soldermask Top")
		(3 "B.Mask" user "Board Geometry/Soldermask Bottom")
		(17 "Dwgs.User" user "User.Drawings")
		(19 "Cmts.User" user "User.Comments")
		(21 "Eco1.User" user "User.Eco1")
		(23 "Eco2.User" user "User.Eco2")
		(25 "Edge.Cuts" user "Board Geometry/Outline")
		(27 "Margin" user)
		(31 "F.CrtYd" user "Package Geometry/Place Bound Top")
		(29 "B.CrtYd" user "Package Geometry/Place Bound Bottom")
		(35 "F.Fab" user "Ref Des/Assembly Top")
		(33 "B.Fab" user "Ref Des/Assembly Bottom")
	)
	(footprint ""
		(layer "F.Cu")
		(at 156.690314 -108.432854 180)
		(property "Reference" "R1130"
			(at 0 0 180)
			(layer "F.SilkS")
			(hide yes)
			(effects
				(font
					(size 1.27 1.27)
				)
			)
		)
		(property "Value" ""
			(at 0 0 180)
			(layer "F.Fab")
			(effects
				(font
					(size 1.27 1.27)
				)
			)
		)
		(duplicate_pad_numbers_are_jumpers no)
		(fp_line
			(start 0.7874 0.4064)
			(end -0.7874 0.4064)
			(stroke
				(width 0.1524)
				(type default)
			)
			(layer "F.SilkS")
		)
		(fp_line
			(start 0.7874 -0.4064)
			(end 0.7874 0.4064)
			(stroke
				(width 0.1524)
				(type default)
			)
			(layer "F.SilkS")
		)
		(fp_line
			(start -0.7874 0.4064)
			(end -0.7874 -0.4064)
			(stroke
				(width 0.1524)
				(type default)
			)
			(layer "F.SilkS")
		)
		(fp_line
			(start -0.7874 -0.4064)
			(end 0.7874 -0.4064)
			(stroke
				(width 0.1524)
				(type default)
			)
			(layer "F.SilkS")
		)
		(fp_line
			(start 0.67945 0.3048)
			(end 0.120396 0.3048)
			(stroke
				(width 0.1)
				(type default)
			)
			(layer "F.Fab")
		)
		(fp_line
			(start 0.67945 -0.3048)
			(end 0.67945 0.3048)
			(stroke
				(width 0.1)
				(type default)
			)
			(layer "F.Fab")
		)
		(fp_line
			(start 0.12065 -0.2794)
			(end 0.12065 -0.3048)
			(stroke
				(width 0.1)
				(type default)
			)
			(layer "F.Fab")
		)
		(fp_line
			(start 0.12065 -0.3048)
			(end 0.67945 -0.3048)
			(stroke
				(width 0.1)
				(type default)
			)
			(layer "F.Fab")
		)
		(fp_line
			(start 0.120396 0.3048)
			(end 0.120396 0.2794)
			(stroke
				(width 0.1)
				(type default)
			)
			(layer "F.Fab")
		)
		(fp_line
			(start 0.120396 0.2794)
			(end -0.12065 0.2794)
			(stroke
				(width 0.1)
				(type default)
			)
			(layer "F.Fab")
		)
		(fp_line
			(start -0.12065 0.3048)
			(end -0.67945 0.3048)
			(stroke
				(width 0.1)
				(type default)
			)
			(layer "F.Fab")
		)
		(fp_line
			(start -0.12065 0.2794)
			(end -0.12065 0.3048)
			(stroke
				(width 0.1)
				(type default)
			)
			(layer "F.Fab")
		)
		(fp_line
			(start -0.12065 -0.2794)
			(end 0.12065 -0.2794)
			(stroke
				(width 0.1)
				(type default)
			)
			(layer "F.Fab")
		)
		(fp_line
			(start -0.12065 -0.305054)
			(end -0.12065 -0.2794)
			(stroke
				(width 0.1)
				(type default)
			)
			(layer "F.Fab")
		)
		(fp_line
			(start -0.67945 0.3048)
			(end -0.67945 -0.305054)
			(stroke
				(width 0.1)
				(type default)
			)
			(layer "F.Fab")
		)
		(fp_line
			(start -0.67945 -0.305054)
			(end -0.12065 -0.305054)
			(stroke
				(width 0.1)
				(type default)
			)
			(layer "F.Fab")
		)
		(pad "1" smd circle
			(at -0.40005 0 180)
			(size 0 0)
			(layers "F.Cu" "F.Mask" "F.Paste")
			(net "P12V_OCP_SFF_EN_R")
		)
		(pad "2" smd circle
			(at 0.40005 0 180)
			(size 0 0)
			(layers "F.Cu" "F.Mask" "F.Paste")
			(net "P12V_OCP_SFF_EN_R3")
		)
	)
	(footprint ""
		(layer "F.Cu")
		(at 428.912782 -107.872276 180)
		(property "Reference" "PR3790"
			(at 0 0 180)
			(layer "F.SilkS")
			(hide yes)
			(effects
				(font
					(size 1.27 1.27)
				)
			)
		)
		(property "Value" ""
			(at 0 0 180)
			(layer "F.Fab")
			(effects
				(font
					(size 1.27 1.27)
				)
			)
		)
		(duplicate_pad_numbers_are_jumpers no)
		(fp_line
			(start 0.7874 0.4064)
			(end -0.7874 0.4064)
			(stroke
				(width 0.1524)
				(type default)
			)
			(layer "F.SilkS")
		)
		(fp_line
			(start 0.7874 -0.4064)
			(end 0.7874 0.4064)
			(stroke
				(width 0.1524)
				(type default)
			)
			(layer "F.SilkS")
		)
		(fp_line
			(start -0.7874 0.4064)
			(end -0.7874 -0.4064)
			(stroke
				(width 0.1524)
				(type default)
			)
			(layer "F.SilkS")
		)
		(fp_line
			(start -0.7874 -0.4064)
			(end 0.7874 -0.4064)
			(stroke
				(width 0.1524)
				(type default)
			)
			(layer "F.SilkS")
		)
		(fp_line
			(start 0.67945 0.3048)
			(end 0.120396 0.3048)
			(stroke
				(width 0.1)
				(type default)
			)
			(layer "F.Fab")
		)
		(fp_line
			(start 0.67945 -0.3048)
			(end 0.67945 0.3048)
			(stroke
				(width 0.1)
				(type default)
			)
			(layer "F.Fab")
		)
		(fp_line
			(start 0.12065 -0.2794)
			(end 0.12065 -0.3048)
			(stroke
				(width 0.1)
				(type default)
			)
			(layer "F.Fab")
		)
		(fp_line
			(start 0.12065 -0.3048)
			(end 0.67945 -0.3048)
			(stroke
				(width 0.1)
				(type default)
			)
			(layer "F.Fab")
		)
		(fp_line
			(start 0.120396 0.3048)
			(end 0.120396 0.2794)
			(stroke
				(width 0.1)
				(type default)
			)
			(layer "F.Fab")
		)
		(fp_line
			(start 0.120396 0.2794)
			(end -0.12065 0.2794)
			(stroke
				(width 0.1)
				(type default)
			)
			(layer "F.Fab")
		)
		(fp_line
			(start -0.12065 0.3048)
			(end -0.67945 0.3048)
			(stroke
				(width 0.1)
				(type default)
			)
			(layer "F.Fab")
		)
		(fp_line
			(start -0.12065 0.2794)
			(end -0.12065 0.3048)
			(stroke
				(width 0.1)
				(type default)
			)
			(layer "F.Fab")
		)
		(fp_line
			(start -0.12065 -0.2794)
			(end 0.12065 -0.2794)
			(stroke
				(width 0.1)
				(type default)
			)
			(layer "F.Fab")
		)
		(fp_line
			(start -0.12065 -0.305054)
			(end -0.12065 -0.2794)
			(stroke
				(width 0.1)
				(type default)
			)
			(layer "F.Fab")
		)
		(fp_line
			(start -0.67945 0.3048)
			(end -0.67945 -0.305054)
			(stroke
				(width 0.1)
				(type default)
			)
			(layer "F.Fab")
		)
		(fp_line
			(start -0.67945 -0.305054)
			(end -0.12065 -0.305054)
			(stroke
				(width 0.1)
				(type default)
			)
			(layer "F.Fab")
		)
		(pad "1" smd circle
			(at -0.40005 0 180)
			(size 0 0)
			(layers "F.Cu" "F.Mask" "F.Paste")
			(net "P3V3_OCP_UV_1")
		)
		(pad "2" smd circle
			(at 0.40005 0 180)
			(size 0 0)
			(layers "F.Cu" "F.Mask" "F.Paste")
			(net "P3V3_OCP_OV_1")
		)
	)
	(footprint ""
		(layer "F.Cu")
		(at 106.892598 -16.98371)
		(property "Reference" "R3553"
			(at 0 0 0)
			(layer "F.SilkS")
			(hide yes)
			(effects
				(font
					(size 1.27 1.27)
				)
			)
		)
		(property "Value" ""
			(at 0 0 0)
			(layer "F.Fab")
			(effects
				(font
					(size 1.27 1.27)
				)
			)
		)
		(duplicate_pad_numbers_are_jumpers no)
		(fp_line
			(start -0.7874 -0.4064)
			(end 0.7874 -0.4064)
			(stroke
				(width 0.1524)
				(type default)
			)
			(layer "F.SilkS")
		)
		(fp_line
			(start -0.7874 0.4064)
			(end -0.7874 -0.4064)
			(stroke
				(width 0.1524)
				(type default)
			)
			(layer "F.SilkS")
		)
		(fp_line
			(start 0.7874 -0.4064)
			(end 0.7874 0.4064)
			(stroke
				(width 0.1524)
				(type default)
			)
			(layer "F.SilkS")
		)
		(fp_line
			(start 0.7874 0.4064)
			(end -0.7874 0.4064)
			(stroke
				(width 0.1524)
				(type default)
			)
			(layer "F.SilkS")
		)
		(fp_line
			(start -0.67945 -0.305054)
			(end -0.12065 -0.305054)
			(stroke
				(width 0.1)
				(type default)
			)
			(layer "F.Fab")
		)
		(fp_line
			(start -0.67945 0.3048)
			(end -0.67945 -0.305054)
			(stroke
				(width 0.1)
				(type default)
			)
			(layer "F.Fab")
		)
		(fp_line
			(start -0.12065 -0.305054)
			(end -0.12065 -0.2794)
			(stroke
				(width 0.1)
				(type default)
			)
			(layer "F.Fab")
		)
		(fp_line
			(start -0.12065 -0.2794)
			(end 0.12065 -0.2794)
			(stroke
				(width 0.1)
				(type default)
			)
			(layer "F.Fab")
		)
		(fp_line
			(start -0.12065 0.2794)
			(end -0.12065 0.3048)
			(stroke
				(width 0.1)
				(type default)
			)
			(layer "F.Fab")
		)
		(fp_line
			(start -0.12065 0.3048)
			(end -0.67945 0.3048)
			(stroke
				(width 0.1)
				(type default)
			)
			(layer "F.Fab")
		)
		(fp_line
			(start 0.120396 0.2794)
			(end -0.12065 0.2794)
			(stroke
				(width 0.1)
				(type default)
			)
			(layer "F.Fab")
		)
		(fp_line
			(start 0.120396 0.3048)
			(end 0.120396 0.2794)
			(stroke
				(width 0.1)
				(type default)
			)
			(layer "F.Fab")
		)
		(fp_line
			(start 0.12065 -0.3048)
			(end 0.67945 -0.3048)
			(stroke
				(width 0.1)
				(type default)
			)
			(layer "F.Fab")
		)
		(fp_line
			(start 0.12065 -0.2794)
			(end 0.12065 -0.3048)
			(stroke
				(width 0.1)
				(type default)
			)
			(layer "F.Fab")
		)
		(fp_line
			(start 0.67945 -0.3048)
			(end 0.67945 0.3048)
			(stroke
				(width 0.1)
				(type default)
			)
			(layer "F.Fab")
		)
		(fp_line
			(start 0.67945 0.3048)
			(end 0.120396 0.3048)
			(stroke
				(width 0.1)
				(type default)
			)
			(layer "F.Fab")
		)
		(pad "1" smd circle
			(at -0.40005 0)
			(size 0 0)
			(layers "F.Cu" "F.Mask" "F.Paste")
			(net "SMB_LM75_3_3V3AUX_SCL")
		)
		(pad "2" smd circle
			(at 0.40005 0)
			(size 0 0)
			(layers "F.Cu" "F.Mask" "F.Paste")
			(net "SMB_LM75_3_3V3AUX_SCL_R1")
		)
	)
	(footprint ""
		(layer "F.Cu")
		(at 362.025438 -412.334964 180)
		(property "Reference" "R9003"
			(at 0 0 180)
			(layer "F.SilkS")
			(hide yes)
			(effects
				(font
					(size 1.27 1.27)
				)
			)
		)
		(property "Value" ""
			(at 0 0 180)
			(layer "F.Fab")
			(effects
				(font
					(size 1.27 1.27)
				)
			)
		)
		(duplicate_pad_numbers_are_jumpers no)
		(fp_line
			(start 0.7874 0.4064)
			(end -0.7874 0.4064)
			(stroke
				(width 0.1524)
				(type default)
			)
			(layer "F.SilkS")
		)
		(fp_line
			(start 0.7874 -0.4064)
			(end 0.7874 0.4064)
			(stroke
				(width 0.1524)
				(type default)
			)
			(layer "F.SilkS")
		)
		(fp_line
			(start -0.7874 0.4064)
			(end -0.7874 -0.4064)
			(stroke
				(width 0.1524)
				(type default)
			)
			(layer "F.SilkS")
		)
		(fp_line
			(start -0.7874 -0.4064)
			(end 0.7874 -0.4064)
			(stroke
				(width 0.1524)
				(type default)
			)
			(layer "F.SilkS")
		)
		(fp_line
			(start 0.67945 0.3048)
			(end 0.120396 0.3048)
			(stroke
				(width 0.1)
				(type default)
			)
			(layer "F.Fab")
		)
		(fp_line
			(start 0.67945 -0.3048)
			(end 0.67945 0.3048)
			(stroke
				(width 0.1)
				(type default)
			)
			(layer "F.Fab")
		)
		(fp_line
			(start 0.12065 -0.2794)
			(end 0.12065 -0.3048)
			(stroke
				(width 0.1)
				(type default)
			)
			(layer "F.Fab")
		)
		(fp_line
			(start 0.12065 -0.3048)
			(end 0.67945 -0.3048)
			(stroke
				(width 0.1)
				(type default)
			)
			(layer "F.Fab")
		)
		(fp_line
			(start 0.120396 0.3048)
			(end 0.120396 0.2794)
			(stroke
				(width 0.1)
				(type default)
			)
			(layer "F.Fab")
		)
		(fp_line
			(start 0.120396 0.2794)
			(end -0.12065 0.2794)
			(stroke
				(width 0.1)
				(type default)
			)
			(layer "F.Fab")
		)
		(fp_line
			(start -0.12065 0.3048)
			(end -0.67945 0.3048)
			(stroke
				(width 0.1)
				(type default)
			)
			(layer "F.Fab")
		)
		(fp_line
			(start -0.12065 0.2794)
			(end -0.12065 0.3048)
			(stroke
				(width 0.1)
				(type default)
			)
			(layer "F.Fab")
		)
		(fp_line
			(start -0.12065 -0.2794)
			(end 0.12065 -0.2794)
			(stroke
				(width 0.1)
				(type default)
			)
			(layer "F.Fab")
		)
		(fp_line
			(start -0.12065 -0.305054)
			(end -0.12065 -0.2794)
			(stroke
				(width 0.1)
				(type default)
			)
			(layer "F.Fab")
		)
		(fp_line
			(start -0.67945 0.3048)
			(end -0.67945 -0.305054)
			(stroke
				(width 0.1)
				(type default)
			)
			(layer "F.Fab")
		)
		(fp_line
			(start -0.67945 -0.305054)
			(end -0.12065 -0.305054)
			(stroke
				(width 0.1)
				(type default)
			)
			(layer "F.Fab")
		)
		(pad "1" smd circle
			(at -0.40005 0 180)
			(size 0 0)
			(layers "F.Cu" "F.Mask" "F.Paste")
			(net "PRSNT_CABLE_SWB_B1_N")
		)
		(pad "2" smd circle
			(at 0.40005 0 180)
			(size 0 0)
			(layers "F.Cu" "F.Mask" "F.Paste")
			(net "GND")
		)
	)
	(footprint ""
		(layer "F.Cu")
		(at 91.317318 -339.413596)
		(property "Reference" "PC425_5"
			(at 0 0 0)
			(layer "F.SilkS")
			(hide yes)
			(effects
				(font
					(size 1.27 1.27)
				)
			)
		)
		(property "Value" ""
			(at 0 0 0)
			(layer "F.Fab")
			(effects
				(font
					(size 1.27 1.27)
				)
			)
		)
		(duplicate_pad_numbers_are_jumpers no)
		(fp_line
			(start -0.7874 -0.4064)
			(end 0.7874 -0.4064)
			(stroke
				(width 0.1524)
				(type default)
			)
			(layer "F.SilkS")
		)
		(fp_line
			(start -0.7874 0.4064)
			(end -0.7874 -0.4064)
			(stroke
				(width 0.1524)
				(type default)
			)
			(layer "F.SilkS")
		)
		(fp_line
			(start 0.7874 -0.4064)
			(end 0.7874 0.4064)
			(stroke
				(width 0.1524)
				(type default)
			)
			(layer "F.SilkS")
		)
		(fp_line
			(start 0.7874 0.4064)
			(end -0.7874 0.4064)
			(stroke
				(width 0.1524)
				(type default)
			)
			(layer "F.SilkS")
		)
		(fp_line
			(start -0.67945 -0.305054)
			(end -0.12065 -0.305054)
			(stroke
				(width 0.1)
				(type default)
			)
			(layer "F.Fab")
		)
		(fp_line
			(start -0.67945 0.3048)
			(end -0.67945 -0.305054)
			(stroke
				(width 0.1)
				(type default)
			)
			(layer "F.Fab")
		)
		(fp_line
			(start -0.12065 -0.305054)
			(end -0.12065 -0.2794)
			(stroke
				(width 0.1)
				(type default)
			)
			(layer "F.Fab")
		)
		(fp_line
			(start -0.12065 -0.2794)
			(end 0.12065 -0.2794)
			(stroke
				(width 0.1)
				(type default)
			)
			(layer "F.Fab")
		)
		(fp_line
			(start -0.12065 0.2794)
			(end -0.12065 0.3048)
			(stroke
				(width 0.1)
				(type default)
			)
			(layer "F.Fab")
		)
		(fp_line
			(start -0.12065 0.3048)
			(end -0.67945 0.3048)
			(stroke
				(width 0.1)
				(type default)
			)
			(layer "F.Fab")
		)
		(fp_line
			(start 0.120396 0.2794)
			(end -0.12065 0.2794)
			(stroke
				(width 0.1)
				(type default)
			)
			(layer "F.Fab")
		)
		(fp_line
			(start 0.120396 0.3048)
			(end 0.120396 0.2794)
			(stroke
				(width 0.1)
				(type default)
			)
			(layer "F.Fab")
		)
		(fp_line
			(start 0.12065 -0.3048)
			(end 0.67945 -0.3048)
			(stroke
				(width 0.1)
				(type default)
			)
			(layer "F.Fab")
		)
		(fp_line
			(start 0.12065 -0.2794)
			(end 0.12065 -0.3048)
			(stroke
				(width 0.1)
				(type default)
			)
			(layer "F.Fab")
		)
		(fp_line
			(start 0.67945 -0.3048)
			(end 0.67945 0.3048)
			(stroke
				(width 0.1)
				(type default)
			)
			(layer "F.Fab")
		)
		(fp_line
			(start 0.67945 0.3048)
			(end 0.120396 0.3048)
			(stroke
				(width 0.1)
				(type default)
			)
			(layer "F.Fab")
		)
		(pad "1" smd circle
			(at -0.40005 0)
			(size 0 0)
			(layers "F.Cu" "F.Mask" "F.Paste")
			(net "SW_P12V_AUX_PVDDCR_CPU1_P1_FLT")
		)
		(pad "2" smd circle
			(at 0.40005 0)
			(size 0 0)
			(layers "F.Cu" "F.Mask" "F.Paste")
			(net "GND")
		)
	)
	(footprint ""
		(layer "F.Cu")
		(at 254.592836 -124.50445)
		(property "Reference" "R3705"
			(at 0 0 0)
			(layer "F.SilkS")
			(hide yes)
			(effects
				(font
					(size 1.27 1.27)
				)
			)
		)
		(property "Value" ""
			(at 0 0 0)
			(layer "F.Fab")
			(effects
				(font
					(size 1.27 1.27)
				)
			)
		)
		(duplicate_pad_numbers_are_jumpers no)
		(fp_line
			(start -0.7874 -0.4064)
			(end 0.7874 -0.4064)
			(stroke
				(width 0.1524)
				(type default)
			)
			(layer "F.SilkS")
		)
		(fp_line
			(start -0.7874 0.4064)
			(end -0.7874 -0.4064)
			(stroke
				(width 0.1524)
				(type default)
			)
			(layer "F.SilkS")
		)
		(fp_line
			(start 0.7874 -0.4064)
			(end 0.7874 0.4064)
			(stroke
				(width 0.1524)
				(type default)
			)
			(layer "F.SilkS")
		)
		(fp_line
			(start 0.7874 0.4064)
			(end -0.7874 0.4064)
			(stroke
				(width 0.1524)
				(type default)
			)
			(layer "F.SilkS")
		)
		(fp_line
			(start -0.67945 -0.305054)
			(end -0.12065 -0.305054)
			(stroke
				(width 0.1)
				(type default)
			)
			(layer "F.Fab")
		)
		(fp_line
			(start -0.67945 0.3048)
			(end -0.67945 -0.305054)
			(stroke
				(width 0.1)
				(type default)
			)
			(layer "F.Fab")
		)
		(fp_line
			(start -0.12065 -0.305054)
			(end -0.12065 -0.2794)
			(stroke
				(width 0.1)
				(type default)
			)
			(layer "F.Fab")
		)
		(fp_line
			(start -0.12065 -0.2794)
			(end 0.12065 -0.2794)
			(stroke
				(width 0.1)
				(type default)
			)
			(layer "F.Fab")
		)
		(fp_line
			(start -0.12065 0.2794)
			(end -0.12065 0.3048)
			(stroke
				(width 0.1)
				(type default)
			)
			(layer "F.Fab")
		)
		(fp_line
			(start -0.12065 0.3048)
			(end -0.67945 0.3048)
			(stroke
				(width 0.1)
				(type default)
			)
			(layer "F.Fab")
		)
		(fp_line
			(start 0.120396 0.2794)
			(end -0.12065 0.2794)
			(stroke
				(width 0.1)
				(type default)
			)
			(layer "F.Fab")
		)
		(fp_line
			(start 0.120396 0.3048)
			(end 0.120396 0.2794)
			(stroke
				(width 0.1)
				(type default)
			)
			(layer "F.Fab")
		)
		(fp_line
			(start 0.12065 -0.3048)
			(end 0.67945 -0.3048)
			(stroke
				(width 0.1)
				(type default)
			)
			(layer "F.Fab")
		)
		(fp_line
			(start 0.12065 -0.2794)
			(end 0.12065 -0.3048)
			(stroke
				(width 0.1)
				(type default)
			)
			(layer "F.Fab")
		)
		(fp_line
			(start 0.67945 -0.3048)
			(end 0.67945 0.3048)
			(stroke
				(width 0.1)
				(type default)
			)
			(layer "F.Fab")
		)
		(fp_line
			(start 0.67945 0.3048)
			(end 0.120396 0.3048)
			(stroke
				(width 0.1)
				(type default)
			)
			(layer "F.Fab")
		)
		(pad "1" smd circle
			(at -0.40005 0)
			(size 0 0)
			(layers "F.Cu" "F.Mask" "F.Paste")
			(net "P3V3_AUX")
		)
		(pad "2" smd circle
			(at 0.40005 0)
			(size 0 0)
			(layers "F.Cu" "F.Mask" "F.Paste")
			(net "RST_SMB_SWITCH_N")
		)
	)
)
